(kicad_pcb
	(version 20260206)
	(generator "pcbnew")
	(generator_version "10.0")
	(general
		(thickness 1.6)
		(legacy_teardrops no)
	)
	(paper "A4")
	(title_block
		(title "01162023_DA0F0TEBIF0_F0T_Expander_BD_F_brd_V02_OCP.brd")
		(comment 1 "Grand Teton / footprints 2948-2955 of 9728")
	)
	(layers
		(0 "F.Cu" signal "TOP")
		(4 "In1.Cu" signal "GND")
		(6 "In2.Cu" signal "VCC")
		(8 "In3.Cu" signal "VCC1")
		(10 "In4.Cu" signal "GND1")
		(12 "In5.Cu" signal "IN1")
		(14 "In6.Cu" signal "GND2")
		(16 "In7.Cu" signal "IN2")
		(18 "In8.Cu" signal "GND3")
		(20 "In9.Cu" signal "IN3")
		(22 "In10.Cu" signal "GND4")
		(24 "In11.Cu" signal "IN4")
		(26 "In12.Cu" signal "GND5")
		(28 "In13.Cu" signal "IN5")
		(30 "In14.Cu" signal "GND6")
		(32 "In15.Cu" signal "IN6")
		(34 "In16.Cu" signal "GND7")
		(2 "B.Cu" signal "BOTTOM")
		(9 "F.Adhes" user "F.Adhesive")
		(11 "B.Adhes" user "B.Adhesive")
		(13 "F.Paste" user "Package Geometry/Pastemask Top")
		(15 "B.Paste" user "Package Geometry/Pastemask Bottom")
		(5 "F.SilkS" user "Ref Des/Silkscreen Top")
		(7 "B.SilkS" user "Ref Des/Silkscreen Bottom")
		(1 "F.Mask" user "Board Geometry/Soldermask Top")
		(3 "B.Mask" user "Board Geometry/Soldermask Bottom")
		(17 "Dwgs.User" user "User.Drawings")
		(19 "Cmts.User" user "User.Comments")
		(21 "Eco1.User" user "User.Eco1")
		(23 "Eco2.User" user "User.Eco2")
		(25 "Edge.Cuts" user "Board Geometry/Outline")
		(27 "Margin" user)
		(31 "F.CrtYd" user "Package Geometry/Place Bound Top")
		(29 "B.CrtYd" user "Package Geometry/Place Bound Bottom")
		(35 "F.Fab" user "Ref Des/Assembly Top")
		(33 "B.Fab" user "Ref Des/Assembly Bottom")
	)
	(footprint ""
		(layer "F.Cu")
		(at 95.926402 -25.432004 -90)
		(property "Reference" "C968"
			(at 0 0 270)
			(layer "F.SilkS")
			(hide yes)
			(effects
				(font
					(size 1.27 1.27)
				)
			)
		)
		(property "Value" ""
			(at 0 0 270)
			(layer "F.Fab")
			(effects
				(font
					(size 1.27 1.27)
				)
			)
		)
		(duplicate_pad_numbers_are_jumpers no)
		(fp_line
			(start -0.7874 0.4064)
			(end -0.7874 -0.4064)
			(stroke
				(width 0.1524)
				(type default)
			)
			(layer "F.SilkS")
		)
		(fp_line
			(start 0.7874 0.4064)
			(end -0.7874 0.4064)
			(stroke
				(width 0.1524)
				(type default)
			)
			(layer "F.SilkS")
		)
		(fp_line
			(start -0.7874 -0.4064)
			(end 0.7874 -0.4064)
			(stroke
				(width 0.1524)
				(type default)
			)
			(layer "F.SilkS")
		)
		(fp_line
			(start 0.7874 -0.4064)
			(end 0.7874 0.4064)
			(stroke
				(width 0.1524)
				(type default)
			)
			(layer "F.SilkS")
		)
		(fp_line
			(start -0.67945 0.3048)
			(end -0.67945 -0.305054)
			(stroke
				(width 0.1)
				(type default)
			)
			(layer "F.Fab")
		)
		(fp_line
			(start -0.12065 0.3048)
			(end -0.67945 0.3048)
			(stroke
				(width 0.1)
				(type default)
			)
			(layer "F.Fab")
		)
		(fp_line
			(start 0.120396 0.3048)
			(end 0.120396 0.2794)
			(stroke
				(width 0.1)
				(type default)
			)
			(layer "F.Fab")
		)
		(fp_line
			(start 0.67945 0.3048)
			(end 0.120396 0.3048)
			(stroke
				(width 0.1)
				(type default)
			)
			(layer "F.Fab")
		)
		(fp_line
			(start -0.12065 0.2794)
			(end -0.12065 0.3048)
			(stroke
				(width 0.1)
				(type default)
			)
			(layer "F.Fab")
		)
		(fp_line
			(start 0.120396 0.2794)
			(end -0.12065 0.2794)
			(stroke
				(width 0.1)
				(type default)
			)
			(layer "F.Fab")
		)
		(fp_line
			(start -0.12065 -0.2794)
			(end 0.12065 -0.2794)
			(stroke
				(width 0.1)
				(type default)
			)
			(layer "F.Fab")
		)
		(fp_line
			(start 0.12065 -0.2794)
			(end 0.12065 -0.3048)
			(stroke
				(width 0.1)
				(type default)
			)
			(layer "F.Fab")
		)
		(fp_line
			(start 0.12065 -0.3048)
			(end 0.67945 -0.3048)
			(stroke
				(width 0.1)
				(type default)
			)
			(layer "F.Fab")
		)
		(fp_line
			(start 0.67945 -0.3048)
			(end 0.67945 0.3048)
			(stroke
				(width 0.1)
				(type default)
			)
			(layer "F.Fab")
		)
		(fp_line
			(start -0.67945 -0.305054)
			(end -0.12065 -0.305054)
			(stroke
				(width 0.1)
				(type default)
			)
			(layer "F.Fab")
		)
		(fp_line
			(start -0.12065 -0.305054)
			(end -0.12065 -0.2794)
			(stroke
				(width 0.1)
				(type default)
			)
			(layer "F.Fab")
		)
		(pad "1" smd circle
			(at -0.40005 0 270)
			(size 0 0)
			(layers "F.Cu" "F.Mask" "F.Paste")
			(net "GND")
		)
		(pad "2" smd circle
			(at 0.40005 0 270)
			(size 0 0)
			(layers "F.Cu" "F.Mask" "F.Paste")
			(net "P3V3_SSD3")
		)
	)
	(footprint ""
		(layer "F.Cu")
		(at 432.166776 -52.543456 180)
		(property "Reference" "PC587"
			(at 0 0 180)
			(layer "F.SilkS")
			(hide yes)
			(effects
				(font
					(size 1.27 1.27)
				)
			)
		)
		(property "Value" ""
			(at 0 0 180)
			(layer "F.Fab")
			(effects
				(font
					(size 1.27 1.27)
				)
			)
		)
		(duplicate_pad_numbers_are_jumpers no)
		(fp_line
			(start 0.7874 0.4064)
			(end -0.7874 0.4064)
			(stroke
				(width 0.1524)
				(type default)
			)
			(layer "F.SilkS")
		)
		(fp_line
			(start 0.7874 -0.4064)
			(end 0.7874 0.4064)
			(stroke
				(width 0.1524)
				(type default)
			)
			(layer "F.SilkS")
		)
		(fp_line
			(start -0.7874 0.4064)
			(end -0.7874 -0.4064)
			(stroke
				(width 0.1524)
				(type default)
			)
			(layer "F.SilkS")
		)
		(fp_line
			(start -0.7874 -0.4064)
			(end 0.7874 -0.4064)
			(stroke
				(width 0.1524)
				(type default)
			)
			(layer "F.SilkS")
		)
		(fp_line
			(start 0.67945 0.3048)
			(end 0.120396 0.3048)
			(stroke
				(width 0.1)
				(type default)
			)
			(layer "F.Fab")
		)
		(fp_line
			(start 0.67945 -0.3048)
			(end 0.67945 0.3048)
			(stroke
				(width 0.1)
				(type default)
			)
			(layer "F.Fab")
		)
		(fp_line
			(start 0.12065 -0.2794)
			(end 0.12065 -0.3048)
			(stroke
				(width 0.1)
				(type default)
			)
			(layer "F.Fab")
		)
		(fp_line
			(start 0.12065 -0.3048)
			(end 0.67945 -0.3048)
			(stroke
				(width 0.1)
				(type default)
			)
			(layer "F.Fab")
		)
		(fp_line
			(start 0.120396 0.3048)
			(end 0.120396 0.2794)
			(stroke
				(width 0.1)
				(type default)
			)
			(layer "F.Fab")
		)
		(fp_line
			(start 0.120396 0.2794)
			(end -0.12065 0.2794)
			(stroke
				(width 0.1)
				(type default)
			)
			(layer "F.Fab")
		)
		(fp_line
			(start -0.12065 0.3048)
			(end -0.67945 0.3048)
			(stroke
				(width 0.1)
				(type default)
			)
			(layer "F.Fab")
		)
		(fp_line
			(start -0.12065 0.2794)
			(end -0.12065 0.3048)
			(stroke
				(width 0.1)
				(type default)
			)
			(layer "F.Fab")
		)
		(fp_line
			(start -0.12065 -0.2794)
			(end 0.12065 -0.2794)
			(stroke
				(width 0.1)
				(type default)
			)
			(layer "F.Fab")
		)
		(fp_line
			(start -0.12065 -0.305054)
			(end -0.12065 -0.2794)
			(stroke
				(width 0.1)
				(type default)
			)
			(layer "F.Fab")
		)
		(fp_line
			(start -0.67945 0.3048)
			(end -0.67945 -0.305054)
			(stroke
				(width 0.1)
				(type default)
			)
			(layer "F.Fab")
		)
		(fp_line
			(start -0.67945 -0.305054)
			(end -0.12065 -0.305054)
			(stroke
				(width 0.1)
				(type default)
			)
			(layer "F.Fab")
		)
		(pad "1" smd circle
			(at -0.40005 0 180)
			(size 0 0)
			(layers "F.Cu" "F.Mask" "F.Paste")
			(net "P3V3_SSD15")
		)
		(pad "2" smd circle
			(at 0.40005 0 180)
			(size 0 0)
			(layers "F.Cu" "F.Mask" "F.Paste")
			(net "GND")
		)
	)
	(footprint ""
		(layer "F.Cu")
		(at 290.548822 -350.098614 90)
		(property "Reference" "C2362"
			(at 0 0 90)
			(layer "F.SilkS")
			(hide yes)
			(effects
				(font
					(size 1.27 1.27)
				)
			)
		)
		(property "Value" ""
			(at 0 0 90)
			(layer "F.Fab")
			(effects
				(font
					(size 1.27 1.27)
				)
			)
		)
		(duplicate_pad_numbers_are_jumpers no)
		(fp_line
			(start 0.299974 -0.150114)
			(end 0.299974 0.150114)
			(stroke
				(width 0.1)
				(type default)
			)
			(layer "F.Fab")
		)
		(fp_line
			(start -0.299974 -0.150114)
			(end 0.299974 -0.150114)
			(stroke
				(width 0.1)
				(type default)
			)
			(layer "F.Fab")
		)
		(fp_line
			(start 0.299974 0.150114)
			(end -0.299974 0.150114)
			(stroke
				(width 0.1)
				(type default)
			)
			(layer "F.Fab")
		)
		(fp_line
			(start -0.299974 0.150114)
			(end -0.299974 -0.150114)
			(stroke
				(width 0.1)
				(type default)
			)
			(layer "F.Fab")
		)
		(pad "1" smd rect
			(at -0.2667 0 90)
			(size 0.3048 0.381)
			(layers "F.Cu" "F.Mask" "F.Paste")
			(net "P5E_PEX2_STN4_TX_DN<69>")
		)
		(pad "2" smd rect
			(at 0.2667 0 90)
			(size 0.3048 0.381)
			(layers "F.Cu" "F.Mask" "F.Paste")
			(net "P5E_PEX2_STN4_TX_C_DN<69>")
		)
	)
	(footprint ""
		(layer "F.Cu")
		(at 267.498576 -137.259314 -90)
		(property "Reference" "C913"
			(at 0 0 270)
			(layer "F.SilkS")
			(hide yes)
			(effects
				(font
					(size 1.27 1.27)
				)
			)
		)
		(property "Value" ""
			(at 0 0 270)
			(layer "F.Fab")
			(effects
				(font
					(size 1.27 1.27)
				)
			)
		)
		(duplicate_pad_numbers_are_jumpers no)
		(fp_line
			(start -0.7874 0.4064)
			(end -0.7874 -0.4064)
			(stroke
				(width 0.1524)
				(type default)
			)
			(layer "F.SilkS")
		)
		(fp_line
			(start 0.7874 0.4064)
			(end -0.7874 0.4064)
			(stroke
				(width 0.1524)
				(type default)
			)
			(layer "F.SilkS")
		)
		(fp_line
			(start -0.7874 -0.4064)
			(end 0.7874 -0.4064)
			(stroke
				(width 0.1524)
				(type default)
			)
			(layer "F.SilkS")
		)
		(fp_line
			(start 0.7874 -0.4064)
			(end 0.7874 0.4064)
			(stroke
				(width 0.1524)
				(type default)
			)
			(layer "F.SilkS")
		)
		(fp_line
			(start -0.67945 0.3048)
			(end -0.67945 -0.305054)
			(stroke
				(width 0.1)
				(type default)
			)
			(layer "F.Fab")
		)
		(fp_line
			(start -0.12065 0.3048)
			(end -0.67945 0.3048)
			(stroke
				(width 0.1)
				(type default)
			)
			(layer "F.Fab")
		)
		(fp_line
			(start 0.120396 0.3048)
			(end 0.120396 0.2794)
			(stroke
				(width 0.1)
				(type default)
			)
			(layer "F.Fab")
		)
		(fp_line
			(start 0.67945 0.3048)
			(end 0.120396 0.3048)
			(stroke
				(width 0.1)
				(type default)
			)
			(layer "F.Fab")
		)
		(fp_line
			(start -0.12065 0.2794)
			(end -0.12065 0.3048)
			(stroke
				(width 0.1)
				(type default)
			)
			(layer "F.Fab")
		)
		(fp_line
			(start 0.120396 0.2794)
			(end -0.12065 0.2794)
			(stroke
				(width 0.1)
				(type default)
			)
			(layer "F.Fab")
		)
		(fp_line
			(start -0.12065 -0.2794)
			(end 0.12065 -0.2794)
			(stroke
				(width 0.1)
				(type default)
			)
			(layer "F.Fab")
		)
		(fp_line
			(start 0.12065 -0.2794)
			(end 0.12065 -0.3048)
			(stroke
				(width 0.1)
				(type default)
			)
			(layer "F.Fab")
		)
		(fp_line
			(start 0.12065 -0.3048)
			(end 0.67945 -0.3048)
			(stroke
				(width 0.1)
				(type default)
			)
			(layer "F.Fab")
		)
		(fp_line
			(start 0.67945 -0.3048)
			(end 0.67945 0.3048)
			(stroke
				(width 0.1)
				(type default)
			)
			(layer "F.Fab")
		)
		(fp_line
			(start -0.67945 -0.305054)
			(end -0.12065 -0.305054)
			(stroke
				(width 0.1)
				(type default)
			)
			(layer "F.Fab")
		)
		(fp_line
			(start -0.12065 -0.305054)
			(end -0.12065 -0.2794)
			(stroke
				(width 0.1)
				(type default)
			)
			(layer "F.Fab")
		)
		(pad "1" smd circle
			(at -0.40005 0 270)
			(size 0 0)
			(layers "F.Cu" "F.Mask" "F.Paste")
			(net "P3V3_NIC4")
		)
		(pad "2" smd circle
			(at 0.40005 0 270)
			(size 0 0)
			(layers "F.Cu" "F.Mask" "F.Paste")
			(net "GND")
		)
	)
	(footprint ""
		(layer "F.Cu")
		(at 82.661506 -135.28675 180)
		(property "Reference" "C18"
			(at 0 0 180)
			(layer "F.SilkS")
			(hide yes)
			(effects
				(font
					(size 1.27 1.27)
				)
			)
		)
		(property "Value" ""
			(at 0 0 180)
			(layer "F.Fab")
			(effects
				(font
					(size 1.27 1.27)
				)
			)
		)
		(duplicate_pad_numbers_are_jumpers no)
		(fp_line
			(start 0.299974 0.150114)
			(end -0.299974 0.150114)
			(stroke
				(width 0.1)
				(type default)
			)
			(layer "F.Fab")
		)
		(fp_line
			(start 0.299974 -0.150114)
			(end 0.299974 0.150114)
			(stroke
				(width 0.1)
				(type default)
			)
			(layer "F.Fab")
		)
		(fp_line
			(start -0.299974 0.150114)
			(end -0.299974 -0.150114)
			(stroke
				(width 0.1)
				(type default)
			)
			(layer "F.Fab")
		)
		(fp_line
			(start -0.299974 -0.150114)
			(end 0.299974 -0.150114)
			(stroke
				(width 0.1)
				(type default)
			)
			(layer "F.Fab")
		)
		(pad "1" smd rect
			(at -0.2667 0 180)
			(size 0.3048 0.381)
			(layers "F.Cu" "F.Mask" "F.Paste")
			(net "P5E_PEX0_STN0_TX_DN<7>")
		)
		(pad "2" smd rect
			(at 0.2667 0 180)
			(size 0.3048 0.381)
			(layers "F.Cu" "F.Mask" "F.Paste")
			(net "P5E_PEX0_STN0_TX_C_DN<7>")
		)
	)
	(footprint ""
		(layer "F.Cu")
		(at 455.447908 -296.887646 -90)
		(property "Reference" "PL24"
			(at -5.334 -7.435088 90)
			(unlocked yes)
			(layer "F.SilkS")
			(effects
				(font
					(size 0.7874 0.5842)
					(thickness 0.1524)
				)
			)
		)
		(property "Value" ""
			(at 0 0 270)
			(layer "F.Fab")
			(effects
				(font
					(size 1.27 1.27)
				)
			)
		)
		(duplicate_pad_numbers_are_jumpers no)
		(fp_line
			(start -6.849872 6.450076)
			(end -6.849872 1.9812)
			(stroke
				(width 0.1524)
				(type default)
			)
			(layer "F.SilkS")
		)
		(fp_line
			(start 6.849872 6.450076)
			(end -6.849872 6.450076)
			(stroke
				(width 0.1524)
				(type default)
			)
			(layer "F.SilkS")
		)
		(fp_line
			(start 6.849872 1.9812)
			(end 6.849872 6.450076)
			(stroke
				(width 0.1524)
				(type default)
			)
			(layer "F.SilkS")
		)
		(fp_line
			(start -6.849872 -1.9812)
			(end -6.849872 -6.450076)
			(stroke
				(width 0.1524)
				(type default)
			)
			(layer "F.SilkS")
		)
		(fp_line
			(start -6.849872 -6.450076)
			(end 6.849872 -6.450076)
			(stroke
				(width 0.1524)
				(type default)
			)
			(layer "F.SilkS")
		)
		(fp_line
			(start 6.849872 -6.450076)
			(end 6.849872 -1.9812)
			(stroke
				(width 0.1524)
				(type default)
			)
			(layer "F.SilkS")
		)
		(fp_line
			(start -6.849872 6.450076)
			(end -6.849872 -6.450076)
			(stroke
				(width 0.1)
				(type default)
			)
			(layer "F.Fab")
		)
		(fp_line
			(start 6.849872 6.450076)
			(end -6.849872 6.450076)
			(stroke
				(width 0.1)
				(type default)
			)
			(layer "F.Fab")
		)
		(fp_line
			(start -6.849872 -6.450076)
			(end 6.849872 -6.450076)
			(stroke
				(width 0.1)
				(type default)
			)
			(layer "F.Fab")
		)
		(fp_line
			(start 6.849872 -6.450076)
			(end 6.849872 6.450076)
			(stroke
				(width 0.1)
				(type default)
			)
			(layer "F.Fab")
		)
		(pad "1" smd rect
			(at -5.407406 0 270)
			(size 2.9464 3.7084)
			(layers "F.Cu" "F.Mask" "F.Paste")
			(net "SW_P1V25_PEX3_PH")
		)
		(pad "2" smd rect
			(at 5.407406 0 270)
			(size 2.9464 3.7084)
			(layers "F.Cu" "F.Mask" "F.Paste")
			(net "P1V25_PEX3_R")
		)
	)
	(footprint ""
		(layer "F.Cu")
		(at 365.506 -215.011)
		(property "Reference" "R4619"
			(at 0 0 0)
			(layer "F.SilkS")
			(hide yes)
			(effects
				(font
					(size 1.27 1.27)
				)
			)
		)
		(property "Value" ""
			(at 0 0 0)
			(layer "F.Fab")
			(effects
				(font
					(size 1.27 1.27)
				)
			)
		)
		(duplicate_pad_numbers_are_jumpers no)
		(fp_line
			(start -0.7874 -0.4064)
			(end 0.7874 -0.4064)
			(stroke
				(width 0.1524)
				(type default)
			)
			(layer "F.SilkS")
		)
		(fp_line
			(start -0.7874 0.4064)
			(end -0.7874 -0.4064)
			(stroke
				(width 0.1524)
				(type default)
			)
			(layer "F.SilkS")
		)
		(fp_line
			(start 0.7874 -0.4064)
			(end 0.7874 0.4064)
			(stroke
				(width 0.1524)
				(type default)
			)
			(layer "F.SilkS")
		)
		(fp_line
			(start 0.7874 0.4064)
			(end -0.7874 0.4064)
			(stroke
				(width 0.1524)
				(type default)
			)
			(layer "F.SilkS")
		)
		(fp_line
			(start -0.67945 -0.305054)
			(end -0.12065 -0.305054)
			(stroke
				(width 0.1)
				(type default)
			)
			(layer "F.Fab")
		)
		(fp_line
			(start -0.67945 0.3048)
			(end -0.67945 -0.305054)
			(stroke
				(width 0.1)
				(type default)
			)
			(layer "F.Fab")
		)
		(fp_line
			(start -0.12065 -0.305054)
			(end -0.12065 -0.2794)
			(stroke
				(width 0.1)
				(type default)
			)
			(layer "F.Fab")
		)
		(fp_line
			(start -0.12065 -0.2794)
			(end 0.12065 -0.2794)
			(stroke
				(width 0.1)
				(type default)
			)
			(layer "F.Fab")
		)
		(fp_line
			(start -0.12065 0.2794)
			(end -0.12065 0.3048)
			(stroke
				(width 0.1)
				(type default)
			)
			(layer "F.Fab")
		)
		(fp_line
			(start -0.12065 0.3048)
			(end -0.67945 0.3048)
			(stroke
				(width 0.1)
				(type default)
			)
			(layer "F.Fab")
		)
		(fp_line
			(start 0.120396 0.2794)
			(end -0.12065 0.2794)
			(stroke
				(width 0.1)
				(type default)
			)
			(layer "F.Fab")
		)
		(fp_line
			(start 0.120396 0.3048)
			(end 0.120396 0.2794)
			(stroke
				(width 0.1)
				(type default)
			)
			(layer "F.Fab")
		)
		(fp_line
			(start 0.12065 -0.3048)
			(end 0.67945 -0.3048)
			(stroke
				(width 0.1)
				(type default)
			)
			(layer "F.Fab")
		)
		(fp_line
			(start 0.12065 -0.2794)
			(end 0.12065 -0.3048)
			(stroke
				(width 0.1)
				(type default)
			)
			(layer "F.Fab")
		)
		(fp_line
			(start 0.67945 -0.3048)
			(end 0.67945 0.3048)
			(stroke
				(width 0.1)
				(type default)
			)
			(layer "F.Fab")
		)
		(fp_line
			(start 0.67945 0.3048)
			(end 0.120396 0.3048)
			(stroke
				(width 0.1)
				(type default)
			)
			(layer "F.Fab")
		)
		(pad "1" smd circle
			(at -0.40005 0)
			(size 0 0)
			(layers "F.Cu" "F.Mask" "F.Paste")
			(net "PEX0_PCA9555_0_INT_N")
		)
		(pad "2" smd circle
			(at 0.40005 0)
			(size 0 0)
			(layers "F.Cu" "F.Mask" "F.Paste")
			(net "P1V8_PEX")
		)
	)
	(footprint ""
		(layer "F.Cu")
		(at 242.61191 -253.996444 -90)
		(property "Reference" "C4356"
			(at 0 0 270)
			(layer "F.SilkS")
			(hide yes)
			(effects
				(font
					(size 1.27 1.27)
				)
			)
		)
		(property "Value" ""
			(at 0 0 270)
			(layer "F.Fab")
			(effects
				(font
					(size 1.27 1.27)
				)
			)
		)
		(duplicate_pad_numbers_are_jumpers no)
		(fp_line
			(start -1.524 0.762)
			(end -1.524 -0.762)
			(stroke
				(width 0.1524)
				(type default)
			)
			(layer "F.SilkS")
		)
		(fp_line
			(start 1.524 0.762)
			(end -1.524 0.762)
			(stroke
				(width 0.1524)
				(type default)
			)
			(layer "F.SilkS")
		)
		(fp_line
			(start -1.524 -0.762)
			(end 1.524 -0.762)
			(stroke
				(width 0.1524)
				(type default)
			)
			(layer "F.SilkS")
		)
		(fp_line
			(start 1.524 -0.762)
			(end 1.524 0.762)
			(stroke
				(width 0.1524)
				(type default)
			)
			(layer "F.SilkS")
		)
		(fp_line
			(start -1.1049 0.724916)
			(end 1.1049 0.724916)
			(stroke
				(width 0.1)
				(type default)
			)
			(layer "F.Fab")
		)
		(fp_line
			(start 1.1049 0.724916)
			(end 1.1049 -0.724916)
			(stroke
				(width 0.1)
				(type default)
			)
			(layer "F.Fab")
		)
		(fp_line
			(start -1.1049 -0.724916)
			(end -1.1049 0.724916)
			(stroke
				(width 0.1)
				(type default)
			)
			(layer "F.Fab")
		)
		(fp_line
			(start 1.1049 -0.724916)
			(end -1.1049 -0.724916)
			(stroke
				(width 0.1)
				(type default)
			)
			(layer "F.Fab")
		)
		(pad "1" smd rect
			(at -0.889 0 90)
			(size 1.016 1.27)
			(layers "F.Cu" "F.Mask" "F.Paste")
			(net "P1V25_SERDES_VDDPLL_PEX2_C10")
		)
		(pad "2" smd rect
			(at 0.889 0 90)
			(size 1.016 1.27)
			(layers "F.Cu" "F.Mask" "F.Paste")
			(net "GND")
		)
		(zone
			(layer "F.Cu")
			(hatch none 0.5)
			(connect_pads
				(clearance 0)
			)
			(min_thickness 0.25)
			(keepout
				(tracks not_allowed)
				(vias allowed)
				(pads allowed)
				(copperpour not_allowed)
				(footprints allowed)
			)
			(placement
				(enabled no)
				(sheetname "")
			)
			(fill
				(thermal_gap 0.5)
				(thermal_bridge_width 0.5)
				(island_removal_mode 0)
			)
			(polygon
				(pts
					(xy 243.336826 -254.326644) (xy 241.886994 -254.326644) (xy 241.886994 -253.666244) (xy 243.336826 -253.666244)
				)
			)
		)
	)
)
